(kicad_pcb
	(version 20241229)
	(generator "pcbnew")
	(generator_version "9.0")
	(general
		(thickness 1.294)
		(legacy_teardrops no)
	)
	(paper "A3")
	(title_block
		(title "Kintex 410T devboard")
		(date "2024-04-03")
		(rev "1.1.2")
		(comment 9 "footprints 480-484 of 975")
	)
	(layers
		(0 "F.Cu" mixed)
		(4 "In1.Cu" power)
		(6 "In2.Cu" power)
		(8 "In3.Cu" mixed)
		(10 "In4.Cu" power)
		(12 "In5.Cu" mixed)
		(14 "In6.Cu" power)
		(16 "In7.Cu" mixed)
		(18 "In8.Cu" power)
		(2 "B.Cu" mixed)
		(9 "F.Adhes" user "F.Adhesive")
		(11 "B.Adhes" user "B.Adhesive")
		(13 "F.Paste" user)
		(15 "B.Paste" user)
		(5 "F.SilkS" user "F.Silkscreen")
		(7 "B.SilkS" user "B.Silkscreen")
		(1 "F.Mask" user)
		(3 "B.Mask" user)
		(17 "Dwgs.User" user "User.Drawings")
		(19 "Cmts.User" user "User.Comments")
		(21 "Eco1.User" user "User.Eco1")
		(23 "Eco2.User" user "User.Eco2")
		(25 "Edge.Cuts" user)
		(27 "Margin" user)
		(31 "F.CrtYd" user "F.Courtyard")
		(29 "B.CrtYd" user "B.Courtyard")
		(35 "F.Fab" user)
		(33 "B.Fab" user)
	)
	(footprint "antmicro-footprints:C_Pol_EIA-B"
		(layer "F.Cu")
		(at 195.961 149.4)
		(property "Reference" "C130"
			(at -2.081 -1.71 0)
			(layer "F.SilkS")
			(effects
				(font
					(size 0.7 0.7)
					(thickness 0.15)
				)
				(justify left bottom)
			)
		)
		(property "Value" "C_Pol_330u_6.3V_KEMET-T520-B"
			(at -2.34 2.45 0)
			(layer "F.Fab")
			(effects
				(font
					(size 0.7 0.7)
					(thickness 0.15)
				)
				(justify left bottom)
			)
		)
		(property "Description" "Tantalum Polymer Capacitor, KO-CAP®, 330 µF, ± 20%, 6.3 V, B, 0.04 ohm, 1411 [3528 Metric]"
			(at 0 0 0)
			(layer "F.Fab")
			(hide yes)
			(effects
				(font
					(size 1.27 1.27)
					(thickness 0.15)
				)
			)
		)
		(property "Author" "Antmicro"
			(at 0 0 0)
			(layer "F.Fab")
			(hide yes)
			(effects
				(font
					(size 1 1)
					(thickness 0.15)
				)
			)
		)
		(property "Dielectric" ""
			(at 0 0 0)
			(layer "F.Fab")
			(hide yes)
			(effects
				(font
					(size 1 1)
					(thickness 0.15)
				)
			)
		)
		(property "License" "Apache-2.0"
			(at 0 0 0)
			(layer "F.Fab")
			(hide yes)
			(effects
				(font
					(size 1 1)
					(thickness 0.15)
				)
			)
		)
		(property "MPN" "T520B337M006ATE040"
			(at 0 0 0)
			(layer "F.Fab")
			(hide yes)
			(effects
				(font
					(size 1 1)
					(thickness 0.15)
				)
			)
		)
		(property "Manufacturer" "KEMET"
			(at 0 0 0)
			(layer "F.Fab")
			(hide yes)
			(effects
				(font
					(size 1 1)
					(thickness 0.15)
				)
			)
		)
		(property "Val" "330u"
			(at 0 0 0)
			(layer "F.Fab")
			(hide yes)
			(effects
				(font
					(size 1 1)
					(thickness 0.15)
				)
			)
		)
		(property "Voltage" "6.3V"
			(at 0 0 0)
			(layer "F.Fab")
			(hide yes)
			(effects
				(font
					(size 1 1)
					(thickness 0.15)
				)
			)
		)
		(sheetname "FPGA supply")
		(sheetfile "fpga-supply.kicad_sch")
		(attr smd)
		(fp_line
			(start -2.521 -1.676)
			(end -2.123 -1.676)
			(stroke
				(width 0.15)
				(type solid)
			)
			(layer "F.SilkS")
		)
		(fp_line
			(start -2.325 -1.475)
			(end -2.325 -1.878)
			(stroke
				(width 0.15)
				(type solid)
			)
			(layer "F.SilkS")
		)
		(fp_line
			(start -1.8 -1.6)
			(end 1.8 -1.6)
			(stroke
				(width 0.15)
				(type solid)
			)
			(layer "F.SilkS")
		)
		(fp_line
			(start -1.8 -1.3)
			(end -1.8 -1.6)
			(stroke
				(width 0.15)
				(type solid)
			)
			(layer "F.SilkS")
		)
		(fp_line
			(start -1.8 1.3)
			(end -1.8 1.6)
			(stroke
				(width 0.15)
				(type solid)
			)
			(layer "F.SilkS")
		)
		(fp_line
			(start 1.8 -1.3)
			(end 1.8 -1.6)
			(stroke
				(width 0.15)
				(type solid)
			)
			(layer "F.SilkS")
		)
		(fp_line
			(start 1.8 1.3)
			(end 1.8 1.6)
			(stroke
				(width 0.15)
				(type solid)
			)
			(layer "F.SilkS")
		)
		(fp_line
			(start 1.8 1.6)
			(end -1.8 1.6)
			(stroke
				(width 0.15)
				(type solid)
			)
			(layer "F.SilkS")
		)
		(fp_line
			(start -2.411 -1.35)
			(end -2.41 1.35)
			(stroke
				(width 0.05)
				(type solid)
			)
			(layer "F.CrtYd")
		)
		(fp_line
			(start -1.97 -1.75)
			(end -1.97 -1.35)
			(stroke
				(width 0.05)
				(type solid)
			)
			(layer "F.CrtYd")
		)
		(fp_line
			(start -1.97 -1.35)
			(end -2.41 -1.35)
			(stroke
				(width 0.05)
				(type solid)
			)
			(layer "F.CrtYd")
		)
		(fp_line
			(start -1.97 1.35)
			(end -2.41 1.35)
			(stroke
				(width 0.05)
				(type solid)
			)
			(layer "F.CrtYd")
		)
		(fp_line
			(start -1.97 1.35)
			(end -1.97 1.75)
			(stroke
				(width 0.05)
				(type solid)
			)
			(layer "F.CrtYd")
		)
		(fp_line
			(start 1.959 -1.75)
			(end -1.971 -1.75)
			(stroke
				(width 0.05)
				(type solid)
			)
			(layer "F.CrtYd")
		)
		(fp_line
			(start 1.959 -1.75)
			(end 1.959 -1.35)
			(stroke
				(width 0.05)
				(type solid)
			)
			(layer "F.CrtYd")
		)
		(fp_line
			(start 1.96 1.35)
			(end 1.96 1.75)
			(stroke
				(width 0.05)
				(type solid)
			)
			(layer "F.CrtYd")
		)
		(fp_line
			(start 1.96 1.75)
			(end -1.97 1.75)
			(stroke
				(width 0.05)
				(type solid)
			)
			(layer "F.CrtYd")
		)
		(fp_line
			(start 2.399 -1.35)
			(end 1.959 -1.35)
			(stroke
				(width 0.05)
				(type solid)
			)
			(layer "F.CrtYd")
		)
		(fp_line
			(start 2.399 -1.35)
			(end 2.4 1.35)
			(stroke
				(width 0.05)
				(type solid)
			)
			(layer "F.CrtYd")
		)
		(fp_line
			(start 2.4 1.35)
			(end 1.96 1.35)
			(stroke
				(width 0.05)
				(type solid)
			)
			(layer "F.CrtYd")
		)
		(fp_line
			(start -1.7 1.324)
			(end -1.551 1.475)
			(stroke
				(width 0.15)
				(type solid)
			)
			(layer "F.Fab")
		)
		(fp_rect
			(start -1.72 -1.5)
			(end 1.719 1.499)
			(stroke
				(width 0.15)
				(type solid)
			)
			(fill no)
			(layer "F.Fab")
		)
		(pad "1" smd roundrect
			(at -1.551 0)
			(size 1.2 2.2)
			(layers "F.Cu" "F.Mask" "F.Paste")
			(roundrect_rratio 0.1)
			(net 650 "+1V0")
			(pintype "passive")
		)
		(pad "2" smd roundrect
			(at 1.55 0)
			(size 1.2 2.2)
			(layers "F.Cu" "F.Mask" "F.Paste")
			(roundrect_rratio 0.1)
			(net 1 "GND")
			(pintype "passive")
		)
	)
	(footprint "antmicro-footprints:R_0402_1005Metric"
		(layer "F.Cu")
		(at 239 134.7 90)
		(descr "Resistor SMD 0402")
		(tags "resistor SMD 0402")
		(property "Reference" "R186"
			(at 1.625 3.825 270)
			(layer "F.SilkS")
			(effects
				(font
					(size 0.7 0.7)
					(thickness 0.15)
				)
				(justify left bottom)
			)
		)
		(property "Value" "R_0R_0402"
			(at 0 1.4 90)
			(layer "F.Fab")
			(effects
				(font
					(size 0.7 0.7)
					(thickness 0.15)
				)
				(justify left bottom)
			)
		)
		(property "Description" "SMD Chip Resistor, Jumper, 0 ohm, 100 mW, 0402 [1005 Metric], Thick Film, General Purpose"
			(at 0 0 90)
			(layer "F.Fab")
			(hide yes)
			(effects
				(font
					(size 1.27 1.27)
					(thickness 0.15)
				)
			)
		)
		(property "Author" "Antmicro"
			(at 373.7 -104.3 0)
			(layer "F.Fab")
			(hide yes)
			(effects
				(font
					(size 1 1)
					(thickness 0.15)
				)
			)
		)
		(property "Current" "1A"
			(at 373.7 -104.3 0)
			(layer "F.Fab")
			(hide yes)
			(effects
				(font
					(size 1 1)
					(thickness 0.15)
				)
			)
		)
		(property "License" "Apache-2.0"
			(at 373.7 -104.3 0)
			(layer "F.Fab")
			(hide yes)
			(effects
				(font
					(size 1 1)
					(thickness 0.15)
				)
			)
		)
		(property "MPN" "ERJ2GE0R00X"
			(at 373.7 -104.3 0)
			(layer "F.Fab")
			(hide yes)
			(effects
				(font
					(size 1 1)
					(thickness 0.15)
				)
			)
		)
		(property "Manufacturer" "Panasonic"
			(at 373.7 -104.3 0)
			(layer "F.Fab")
			(hide yes)
			(effects
				(font
					(size 1 1)
					(thickness 0.15)
				)
			)
		)
		(property "Tolerance" ""
			(at 373.7 -104.3 0)
			(layer "F.Fab")
			(hide yes)
			(effects
				(font
					(size 1 1)
					(thickness 0.15)
				)
			)
		)
		(property "Val" "0R"
			(at 373.7 -104.3 0)
			(layer "F.Fab")
			(hide yes)
			(effects
				(font
					(size 1 1)
					(thickness 0.15)
				)
			)
		)
		(sheetname "USB PHY")
		(sheetfile "usb-phy.kicad_sch")
		(attr smd)
		(fp_rect
			(start -0.925 -0.47)
			(end 0.925 0.47)
			(stroke
				(width 0.05)
				(type default)
			)
			(fill no)
			(layer "F.CrtYd")
		)
		(fp_rect
			(start -0.5 -0.25)
			(end 0.5 0.25)
			(stroke
				(width 0.15)
				(type solid)
			)
			(fill no)
			(layer "F.Fab")
		)
		(pad "1" smd roundrect
			(at -0.48 0 90)
			(size 0.59 0.64)
			(layers "F.Cu" "F.Mask" "F.Paste")
			(roundrect_rratio 0.25)
			(net 379 "Net-(U24-OE)")
			(pintype "passive")
		)
		(pad "2" smd roundrect
			(at 0.48 0 90)
			(size 0.59 0.64)
			(layers "F.Cu" "F.Mask" "F.Paste")
			(roundrect_rratio 0.25)
			(net 925 "/USB PHY/BDBUS3")
			(pintype "passive")
		)
	)
	(footprint "antmicro-footprints:R_0402_1005Metric"
		(layer "F.Cu")
		(at 236 140 180)
		(descr "Resistor SMD 0402")
		(tags "resistor SMD 0402")
		(property "Reference" "R193"
			(at 1.9 -2.35 180)
			(layer "F.SilkS")
			(effects
				(font
					(size 0.7 0.7)
					(thickness 0.15)
				)
				(justify left bottom)
			)
		)
		(property "Value" "R_4k7_0402"
			(at 0 1.4 180)
			(layer "F.Fab")
			(effects
				(font
					(size 0.7 0.7)
					(thickness 0.15)
				)
				(justify left bottom)
			)
		)
		(property "Description" "SMD Chip Resistor, 4.7 kohm, ± 1%, 62.5 mW, 0402 [1005 Metric], Thick Film, General Purpose"
			(at 0 0 180)
			(layer "F.Fab")
			(hide yes)
			(effects
				(font
					(size 1.27 1.27)
					(thickness 0.15)
				)
			)
		)
		(property "Author" "Antmicro"
			(at 472 280 0)
			(layer "F.Fab")
			(hide yes)
			(effects
				(font
					(size 1 1)
					(thickness 0.15)
				)
			)
		)
		(property "License" "Apache-2.0"
			(at 472 280 0)
			(layer "F.Fab")
			(hide yes)
			(effects
				(font
					(size 1 1)
					(thickness 0.15)
				)
			)
		)
		(property "MPN" "CR0402-FX-4701GLF"
			(at 472 280 0)
			(layer "F.Fab")
			(hide yes)
			(effects
				(font
					(size 1 1)
					(thickness 0.15)
				)
			)
		)
		(property "Manufacturer" "Bourns"
			(at 472 280 0)
			(layer "F.Fab")
			(hide yes)
			(effects
				(font
					(size 1 1)
					(thickness 0.15)
				)
			)
		)
		(property "Tolerance" "1%"
			(at 472 280 0)
			(layer "F.Fab")
			(hide yes)
			(effects
				(font
					(size 1 1)
					(thickness 0.15)
				)
			)
		)
		(property "Val" "4k7"
			(at 472 280 0)
			(layer "F.Fab")
			(hide yes)
			(effects
				(font
					(size 1 1)
					(thickness 0.15)
				)
			)
		)
		(sheetname "USB PHY")
		(sheetfile "usb-phy.kicad_sch")
		(attr smd)
		(fp_rect
			(start -0.925 -0.47)
			(end 0.925 0.47)
			(stroke
				(width 0.05)
				(type default)
			)
			(fill no)
			(layer "F.CrtYd")
		)
		(fp_rect
			(start -0.5 -0.25)
			(end 0.5 0.25)
			(stroke
				(width 0.15)
				(type solid)
			)
			(fill no)
			(layer "F.Fab")
		)
		(pad "1" smd roundrect
			(at -0.48 0 180)
			(size 0.59 0.64)
			(layers "F.Cu" "F.Mask" "F.Paste")
			(roundrect_rratio 0.25)
			(net 1205 "Net-(D38-Pad1)")
			(pintype "passive")
		)
		(pad "2" smd roundrect
			(at 0.48 0 180)
			(size 0.59 0.64)
			(layers "F.Cu" "F.Mask" "F.Paste")
			(roundrect_rratio 0.25)
			(net 1338 "/I2C.SCL")
			(pintype "passive")
		)
	)
	(footprint "antmicro-footprints:R_Array_4x0201_Panasonic_EXB18V"
		(layer "F.Cu")
		(at 247.9 144.302)
		(property "Reference" "R42"
			(at -13.7 -40.902 0)
			(layer "F.SilkS")
			(effects
				(font
					(size 0.7 0.7)
					(thickness 0.15)
				)
				(justify right bottom)
			)
		)
		(property "Value" "R_4x33R_0201_array"
			(at -1.1 1.8 0)
			(layer "F.Fab")
			(effects
				(font
					(size 0.7 0.7)
					(thickness 0.15)
				)
				(justify left bottom)
			)
		)
		(property "Description" "Fixed Network Resistor, 33 ohm, Isolated, 4 Resistors, 0502 [1406 Metric], Flat, ± 5%"
			(at 0 0 0)
			(layer "F.Fab")
			(hide yes)
			(effects
				(font
					(size 1.27 1.27)
					(thickness 0.15)
				)
			)
		)
		(property "Author" "Antmicro"
			(at 0 0 0)
			(layer "F.Fab")
			(hide yes)
			(effects
				(font
					(size 1 1)
					(thickness 0.15)
				)
			)
		)
		(property "License" "Apache-2.0"
			(at 0 0 0)
			(layer "F.Fab")
			(hide yes)
			(effects
				(font
					(size 1 1)
					(thickness 0.15)
				)
			)
		)
		(property "MPN" "EXB-18V330JX"
			(at 0 0 0)
			(layer "F.Fab")
			(hide yes)
			(effects
				(font
					(size 1 1)
					(thickness 0.15)
				)
			)
		)
		(property "Manufacturer" "Panasonic"
			(at 0 0 0)
			(layer "F.Fab")
			(hide yes)
			(effects
				(font
					(size 1 1)
					(thickness 0.15)
				)
			)
		)
		(property "Val" "R_4x33R_0201"
			(at 0 0 0)
			(layer "F.Fab")
			(hide yes)
			(effects
				(font
					(size 1 1)
					(thickness 0.15)
				)
			)
		)
		(sheetname "Supervisior MCU")
		(sheetfile "supervisor-mcu.kicad_sch")
		(attr smd)
		(fp_line
			(start -0.8 -0.45)
			(end -0.8 0.45)
			(stroke
				(width 0.12)
				(type solid)
			)
			(layer "F.SilkS")
		)
		(fp_line
			(start 0.8 -0.45)
			(end 0.8 0.45)
			(stroke
				(width 0.12)
				(type solid)
			)
			(layer "F.SilkS")
		)
		(fp_rect
			(start -0.898 -0.66)
			(end 0.898 0.65)
			(stroke
				(width 0.05)
				(type solid)
			)
			(fill no)
			(layer "F.CrtYd")
		)
		(pad "1" smd roundrect
			(at -0.6 0.298)
			(size 0.2 0.4)
			(layers "F.Cu" "F.Mask" "F.Paste")
			(roundrect_rratio 0.25)
			(net 1106 "/Supervisior MCU/TEMP_ALERT_N")
			(pinfunction "R1.1")
			(pintype "passive")
		)
		(pad "2" smd roundrect
			(at -0.202 0.298)
			(size 0.2 0.4)
			(layers "F.Cu" "F.Mask" "F.Paste")
			(roundrect_rratio 0.25)
			(net 1103 "/Supervisior MCU/FPGA_M0")
			(pinfunction "R2.1")
			(pintype "passive")
		)
		(pad "3" smd roundrect
			(at 0.2 0.298)
			(size 0.2 0.4)
			(layers "F.Cu" "F.Mask" "F.Paste")
			(roundrect_rratio 0.25)
			(net 1116 "/Supervisior MCU/USB_SPARE2")
			(pinfunction "R3.1")
			(pintype "passive")
		)
		(pad "4" smd roundrect
			(at 0.598 0.298)
			(size 0.2 0.4)
			(layers "F.Cu" "F.Mask" "F.Paste")
			(roundrect_rratio 0.25)
			(net 1115 "/Supervisior MCU/USB_SPARE1")
			(pinfunction "R4.1")
			(pintype "passive")
		)
		(pad "5" smd roundrect
			(at 0.598 -0.3)
			(size 0.2 0.4)
			(layers "F.Cu" "F.Mask" "F.Paste")
			(roundrect_rratio 0.25)
			(net 1383 "/SUP_MCU.SPARE1")
			(pinfunction "R4.2")
			(pintype "passive")
		)
		(pad "6" smd roundrect
			(at 0.2 -0.3)
			(size 0.2 0.4)
			(layers "F.Cu" "F.Mask" "F.Paste")
			(roundrect_rratio 0.25)
			(net 1384 "/SUP_MCU.SPARE2")
			(pinfunction "R3.2")
			(pintype "passive")
		)
		(pad "7" smd roundrect
			(at -0.202 -0.3)
			(size 0.2 0.4)
			(layers "F.Cu" "F.Mask" "F.Paste")
			(roundrect_rratio 0.25)
			(net 1312 "/SUP_MCU.FPGA_M0")
			(pinfunction "R2.2")
			(pintype "passive")
		)
		(pad "8" smd roundrect
			(at -0.6 -0.3)
			(size 0.2 0.4)
			(layers "F.Cu" "F.Mask" "F.Paste")
			(roundrect_rratio 0.25)
			(net 1335 "/SUP_MCU.TEMP_ALERT_N")
			(pinfunction "R1.2")
			(pintype "passive")
		)
	)
	(footprint "antmicro-footprints:R_0402_1005Metric"
		(layer "F.Cu")
		(at 212.9 165.4 90)
		(descr "Resistor SMD 0402")
		(tags "resistor SMD 0402")
		(property "Reference" "R83"
			(at -0.4 -5.25 90)
			(layer "F.SilkS")
			(effects
				(font
					(size 0.7 0.7)
					(thickness 0.15)
				)
				(justify left bottom)
			)
		)
		(property "Value" "R_0R_0402"
			(at 0 1.4 90)
			(layer "F.Fab")
			(effects
				(font
					(size 0.7 0.7)
					(thickness 0.15)
				)
				(justify left bottom)
			)
		)
		(property "Description" "SMD Chip Resistor, Jumper, 0 ohm, 100 mW, 0402 [1005 Metric], Thick Film, General Purpose"
			(at 0 0 90)
			(layer "F.Fab")
			(hide yes)
			(effects
				(font
					(size 1.27 1.27)
					(thickness 0.15)
				)
			)
		)
		(property "Author" "Antmicro"
			(at 378.3 -47.5 0)
			(layer "F.Fab")
			(hide yes)
			(effects
				(font
					(size 1 1)
					(thickness 0.15)
				)
			)
		)
		(property "Current" "1A"
			(at 378.3 -47.5 0)
			(layer "F.Fab")
			(hide yes)
			(effects
				(font
					(size 1 1)
					(thickness 0.15)
				)
			)
		)
		(property "License" "Apache-2.0"
			(at 378.3 -47.5 0)
			(layer "F.Fab")
			(hide yes)
			(effects
				(font
					(size 1 1)
					(thickness 0.15)
				)
			)
		)
		(property "MPN" "ERJ2GE0R00X"
			(at 378.3 -47.5 0)
			(layer "F.Fab")
			(hide yes)
			(effects
				(font
					(size 1 1)
					(thickness 0.15)
				)
			)
		)
		(property "Manufacturer" "Panasonic"
			(at 378.3 -47.5 0)
			(layer "F.Fab")
			(hide yes)
			(effects
				(font
					(size 1 1)
					(thickness 0.15)
				)
			)
		)
		(property "Tolerance" ""
			(at 378.3 -47.5 0)
			(layer "F.Fab")
			(hide yes)
			(effects
				(font
					(size 1 1)
					(thickness 0.15)
				)
			)
		)
		(property "Val" "0R"
			(at 378.3 -47.5 0)
			(layer "F.Fab")
			(hide yes)
			(effects
				(font
					(size 1 1)
					(thickness 0.15)
				)
			)
		)
		(sheetname "SPI Flash + SD Card")
		(sheetfile "spi-flash.kicad_sch")
		(attr smd)
		(fp_rect
			(start -0.925 -0.47)
			(end 0.925 0.47)
			(stroke
				(width 0.05)
				(type default)
			)
			(fill no)
			(layer "F.CrtYd")
		)
		(fp_rect
			(start -0.5 -0.25)
			(end 0.5 0.25)
			(stroke
				(width 0.15)
				(type solid)
			)
			(fill no)
			(layer "F.Fab")
		)
		(pad "1" smd roundrect
			(at -0.48 0 90)
			(size 0.59 0.64)
			(layers "F.Cu" "F.Mask" "F.Paste")
			(roundrect_rratio 0.25)
			(net 411 "/FPGA Bank 33 & 34/USR_FLASH_0.DQ1")
			(pintype "passive")
		)
		(pad "2" smd roundrect
			(at 0.48 0 90)
			(size 0.59 0.64)
			(layers "F.Cu" "F.Mask" "F.Paste")
			(roundrect_rratio 0.25)
			(net 903 "/SPI Flash + SD Card/USR_FLASH_0_DQ1")
			(pintype "passive")
		)
	)
)
